FILE_TYPE = CONNECTIVITY;
{Allegro Design Entry HDL 17.2-2016 S067 (3860444) 4/26/2020}
"PAGE_NUMBER" = 164;
0"NC";
1"SG\g";
2"SG\g";
3"SG\g";
4"SG\g";
5"SG\g";
6"XP2R5V_FPGA\g";
7"XP1R8V_FPGA\g";
8"XP1R2V_FPGA\g";
9"XP1R0V_FPGA\g";
10"XP1R0V_FPGA\g";
11"XP3R3V_FPGA\g";
12"SG\g";
13"FPGA_MGTAVTT\g";
14"SG\g";
15"SG\g";
16"XP1R0V_FPGA_MGTAVCC";
17"XP1R0V_FPGA_VCCINT";
18"XP1R8V_FPGA_VCCAUX";
%"GND_SG"
"1","(-11000,-1050)","0","cls","I1";
;
HDL_POWER"SG"
BODY_TYPE"PLUMBING"
CDS_LIB"cls"
CDS_LMAN_SYM_OUTLINE"0,0,100,-50";
"SGND"15;
%"FERRITEBEAD"
"1","(-7500,7450)","0","passive","I102";
;
PACKAGE"0603"
VALUE"120OHM"
TOLERANCE"25%"
CDS_LMAN_SYM_OUTLINE"0,0,200,-100"
CDS_LIB"passive"
CLS_PN"G191-10100-01"
$LOCATION"L33"
CDS_LOCATION"L33"
$SEC"1"
CDS_SEC"1";
"2"
$PN"2"7;
"1"
$PN"1"18;
%"GND_SG"
"1","(-11000,3100)","0","cls","I134";
;
HDL_POWER"SG"
BODY_TYPE"PLUMBING"
CDS_LMAN_SYM_OUTLINE"0,0,100,-50"
CDS_LIB"cls";
"SGND"14;
%"VCC"
"1","(-11250,-200)","0","cls","I135";
;
HDL_POWER"FPGA_MGTAVTT"
VOLTAGE"1.2"
BODY_TYPE"PLUMBING"
CDS_LMAN_SYM_OUTLINE"-250,250,250,-250"
CDS_LIB"cls";
"$PIN0"13;
%"GND_SG"
"1","(-14500,-950)","0","cls","I137";
;
HDL_POWER"SG"
BODY_TYPE"PLUMBING"
CDS_LIB"cls"
CDS_LMAN_SYM_OUTLINE"0,0,100,-50";
"SGND"12;
%"XC7A200T_2FBG484C_FBG484"
"5","(-12950,8100)","5","pld","I138";
;
VALUE"XC7A100T-1FGG484I"
CLS_PN"G240-10069-01"
CDS_LIB"pld"
CDS_LMAN_SYM_OUTLINE"0,0,9000,-1100"
$LOCATION"U24"
CDS_LOCATION"U24"
$SEC"5"
CDS_SEC"5";
"MGTAVTT_6"
$PN"C8"13;
"MGTAVTT_5"
$PN"C4"13;
"MGTAVTT_4"
$PN"B9"13;
"MGTAVTT_3"
$PN"B7"13;
"MGTAVTT_2"
$PN"B5"13;
"MGTAVTT_1"
$PN"B11"13;
"MGTAVCC_5"
$PN"F9"16;
"MGTAVCC_4"
$PN"F7"16;
"MGTAVCC_3"
$PN"E8"16;
"MGTAVCC_2"
$PN"D6"16;
"MGTAVCC_1"
$PN"D10"16;
"VCCO_35_6"
$PN"N1"6;
"VCCO_35_5"
$PN"M4"6;
"VCCO_35_4"
$PN"J3"6;
"VCCO_35_3"
$PN"H6"6;
"VCCO_35_2"
$PN"F2"6;
"VCCO_35_1"
$PN"C1"6;
"VCCO_34_6"
$PN"W3"6;
"VCCO_34_5"
$PN"V6"6;
"VCCO_34_4"
$PN"T2"6;
"VCCO_34_3"
$PN"R5"6;
"VCCO_34_2"
$PN"AB4"6;
"VCCO_34_1"
$PN"AA7"6;
"VCCO_16_6"
$PN"F22"11;
"VCCO_16_5"
$PN"E15"11;
"VCCO_16_4"
$PN"D18"11;
"VCCO_16_3"
$PN"C21"11;
"VCCO_16_2"
$PN"B14"11;
"VCCO_16_1"
$PN"A17"11;
"VCCO_15_6"
$PN"N21"11;
"VCCO_15_5"
$PN"L17"11;
"VCCO_15_4"
$PN"K20"11;
"VCCO_15_3"
$PN"J13"11;
"VCCO_15_2"
$PN"H16"11;
"VCCO_15_1"
$PN"G19"11;
"VCCO_14_6"
$PN"Y20"11;
"VCCO_14_5"
$PN"U19"11;
"VCCO_14_4"
$PN"T22"11;
"VCCO_14_3"
$PN"R15"11;
"VCCO_14_2"
$PN"P18"11;
"VCCO_14_1"
$PN"M14"11;
"VCCO_13_5"
$PN"Y10"11;
"VCCO_13_4"
$PN"W13"11;
"VCCO_13_3"
$PN"V16"11;
"VCCO_13_2"
$PN"AB14"11;
"VCCO_13_1"
$PN"AA17"11;
"VCCO_0_2"
$PN"T12"11;
"VCCO_0_1"
$PN"F12"11;
"VCCINT_14"
$PN"T8"17;
"VCCINT_13"
$PN"T10"17;
"VCCINT_12"
$PN"R9"17;
"VCCINT_11"
$PN"R7"17;
"VCCINT_10"
$PN"P8"17;
"VCCINT_9"
$PN"P10"17;
"VCCINT_8"
$PN"N7"17;
"VCCINT_7"
$PN"M8"17;
"VCCINT_6"
$PN"L7"17;
"VCCINT_5"
$PN"K8"17;
"VCCINT_4"
$PN"J9"17;
"VCCINT_3"
$PN"J7"17;
"VCCINT_2"
$PN"H8"17;
"VCCINT_1"
$PN"H10"17;
"VCCBRAM_3"
$PN"N11"17;
"VCCBRAM_2"
$PN"L11"17;
"VCCBRAM_1"
$PN"J11"17;
"VCCBATT_0"
$PN"E12"18;
"VCCAUX_5"
$PN"R11"18;
"VCCAUX_4"
$PN"P12"18;
"VCCAUX_3"
$PN"M12"18;
"VCCAUX_2"
$PN"K12"18;
"VCCAUX_1"
$PN"H12"18;
"VCCADC_0"
$PN"K10"18;
"GNDADC_0"
$PN"K9"12;
"GND_87"
$PN"Y5"12;
"GND_86"
$PN"Y15"12;
"GND_85"
$PN"W8"12;
"GND_84"
$PN"W18"12;
"GND_83"
$PN"V21"12;
"GND_82"
$PN"V11"12;
"GND_81"
$PN"V1"12;
"GND_80"
$PN"U4"12;
"GND_79"
$PN"U14"12;
"GND_78"
$PN"T9"12;
"GND_77"
$PN"T7"12;
"GND_76"
$PN"T17"12;
"GND_75"
$PN"T11"12;
"GND_74"
$PN"R8"12;
"GND_73"
$PN"R20"12;
"GND_72"
$PN"R12"12;
"GND_71"
$PN"R10"12;
"GND_70"
$PN"P9"12;
"GND_69"
$PN"P7"12;
"GND_68"
$PN"P3"12;
"GND_67"
$PN"P13"12;
"GND_66"
$PN"P11"12;
"GND_65"
$PN"N8"12;
"GND_64"
$PN"N6"12;
"GND_63"
$PN"N16"12;
"GND_62"
$PN"M7"12;
"GND_61"
$PN"M19"12;
"GND_60"
$PN"M11"12;
"GND_59"
$PN"L8"12;
"GND_58"
$PN"L22"12;
"GND_57"
$PN"L2"12;
"GND_56"
$PN"K7"12;
"GND_55"
$PN"K5"12;
"GND_54"
$PN"K15"12;
"GND_53"
$PN"K11"12;
"GND_52"
$PN"J8"12;
"GND_51"
$PN"J18"12;
"GND_50"
$PN"J12"12;
"GND_49"
$PN"J10"12;
"GND_48"
$PN"H9"12;
"GND_47"
$PN"H7"12;
"GND_46"
$PN"H21"12;
"GND_45"
$PN"H11"12;
"GND_44"
$PN"H1"12;
"GND_43"
$PN"G9"12;
"GND_42"
$PN"G8"12;
"GND_41"
$PN"G7"12;
"GND_40"
$PN"G6"12;
"GND_39"
$PN"G5"12;
"GND_38"
$PN"G14"12;
"GND_37"
$PN"G12"12;
"GND_36"
$PN"G10"12;
"GND_35"
$PN"F5"12;
"GND_34"
$PN"F17"12;
"GND_33"
$PN"F11"12;
"GND_32"
$PN"E9"12;
"GND_31"
$PN"E7"12;
"GND_30"
$PN"E5"12;
"GND_29"
$PN"E4"12;
"GND_28"
$PN"E20"12;
"GND_27"
$PN"E11"12;
"GND_26"
$PN"D8"12;
"GND_25"
$PN"D4"12;
"GND_24"
$PN"D3"12;
"GND_23"
$PN"D13"12;
"GND_22"
$PN"D12"12;
"GND_21"
$PN"C6"12;
"GND_20"
$PN"C3"12;
"GND_19"
$PN"C16"12;
"GND_18"
$PN"C12"12;
"GND_17"
$PN"C10"12;
"GND_16"
$PN"B3"12;
"GND_15"
$PN"B19"12;
"GND_14"
$PN"B12"12;
"GND_13"
$PN"AB9"12;
"GND_12"
$PN"AB19"12;
"GND_11"
$PN"AA22"12;
"GND_10"
$PN"AA2"12;
"GND_9"
$PN"AA12"12;
"GND_8"
$PN"A9"12;
"GND_7"
$PN"A7"12;
"GND_6"
$PN"A5"12;
"GND_5"
$PN"A3"12;
"GND_4"
$PN"A22"12;
"GND_3"
$PN"A2"12;
"GND_2"
$PN"A12"12;
"GND_1"
$PN"A11"12;
%"FERRITEBEAD"
"1","(-3350,6000)","0","passive","I139";
;
PACKAGE"0603"
VALUE"120OHM"
TOLERANCE"25%"
CDS_LIB"passive"
CDS_LMAN_SYM_OUTLINE"0,0,200,-100"
CLS_PN"G191-10100-01"
$LOCATION"L12"
CDS_LOCATION"L12"
$SEC"1"
CDS_SEC"1";
"2"
$PN"2"10;
"1"
$PN"1"17;
%"CAPACITOR"
"2","(-3950,5700)","0","passive","I172";
;
VOLTAGE"6.3V"
PACKAGE"1210"
VALUE"100UF"
TOLERANCE"20%"
CLS_PN"G109-0G107-BM"
CDS_LMAN_SYM_OUTLINE"-50,0,50,-50"
CDS_LIB"passive"
$LOCATION"C176"
CDS_LOCATION"C176"
$SEC"1"
CDS_SEC"1";
"2"
$PN"2"1;
"1"
$PN"1"17;
%"CAPACITOR"
"2","(-4300,5700)","0","passive","I173";
;
VOLTAGE"6.3V"
PACKAGE"1210"
VALUE"100UF"
TOLERANCE"20%"
CLS_PN"G109-0G107-BM"
CDS_LIB"passive"
CDS_LMAN_SYM_OUTLINE"-50,0,50,-50"
$LOCATION"C175"
CDS_LOCATION"C175"
$SEC"1"
CDS_SEC"1";
"2"
$PN"2"1;
"1"
$PN"1"17;
%"CAPACITOR"
"2","(-5000,4300)","0","passive","I174";
;
VALUE"100UF"
VOLTAGE"6.3V"
PACKAGE"1210"
CLS_PN"G109-0G107-BM"
CDS_LMAN_SYM_OUTLINE"-50,0,50,-50"
CDS_LIB"passive"
TOLERANCE"20%"
$LOCATION"C172"
CDS_LOCATION"C172"
$SEC"1"
CDS_SEC"1";
"2"
$PN"2"3;
"1"
$PN"1"11;
%"CAPACITOR"
"2","(-6400,7150)","0","passive","I176";
;
VOLTAGE"10V"
VALUE"22UF"
PACKAGE"0805"
CLS_PN"G107-0F226-CM"
TOLERANCE"20%"
CDS_LIB"passive"
CDS_LMAN_SYM_OUTLINE"-50,0,50,-50"
$LOCATION"C158"
CDS_LOCATION"C158"
$SEC"1"
CDS_SEC"1";
"2"
$PN"2"2;
"1"
$PN"1"7;
%"CAPACITOR"
"2","(-8750,7150)","0","passive","I177";
;
VOLTAGE"6.3V"
VALUE"4.7UF"
PACKAGE"0402"
CLS_PN"G105-0F475-BM"
CDS_LIB"passive"
CDS_LMAN_SYM_OUTLINE"-50,0,50,-50"
TOLERANCE"20%"
$LOCATION"C120"
CDS_LOCATION"C120"
$SEC"1"
CDS_SEC"1";
"2"
$PN"2"2;
"1"
$PN"1"18;
%"CAPACITOR"
"2","(-4600,4300)","0","passive","I178";
;
VOLTAGE"6.3V"
VALUE"100UF"
PACKAGE"1210"
TOLERANCE"20%"
CLS_PN"G109-0G107-BM"
CDS_LMAN_SYM_OUTLINE"-50,0,50,-50"
CDS_LIB"passive"
$LOCATION"C174"
CDS_LOCATION"C174"
$SEC"1"
CDS_SEC"1";
"2"
$PN"2"3;
"1"
$PN"1"11;
%"CAPACITOR"
"2","(-10950,5700)","0","passive","I182";
;
VALUE"0.1UF"
VOLTAGE"10V"
PACKAGE"0402"
TOLERANCE"10%"
CDS_LIB"passive"
CDS_LMAN_SYM_OUTLINE"-50,0,50,-50"
CLS_PN"G105-0B104-CK"
$LOCATION"C201"
CDS_LOCATION"C201"
$SEC"1"
CDS_SEC"1";
"2"
$PN"2"1;
"1"
$PN"1"17;
%"CAPACITOR"
"2","(-10600,5700)","0","passive","I183";
;
VALUE"0.1UF"
VOLTAGE"10V"
PACKAGE"0402"
TOLERANCE"10%"
CDS_LIB"passive"
CDS_LMAN_SYM_OUTLINE"-50,0,50,-50"
CLS_PN"G105-0B104-CK"
$LOCATION"C207"
CDS_LOCATION"C207"
$SEC"1"
CDS_SEC"1";
"2"
$PN"2"1;
"1"
$PN"1"17;
%"CAPACITOR"
"2","(-10200,5700)","0","passive","I184";
;
VALUE"0.1UF"
VOLTAGE"10V"
PACKAGE"0402"
TOLERANCE"10%"
CDS_LIB"passive"
CDS_LMAN_SYM_OUTLINE"-50,0,50,-50"
CLS_PN"G105-0B104-CK"
$LOCATION"C214"
CDS_LOCATION"C214"
$SEC"1"
CDS_SEC"1";
"2"
$PN"2"1;
"1"
$PN"1"17;
%"CAPACITOR"
"2","(-9800,5700)","0","passive","I185";
;
VALUE"0.1UF"
VOLTAGE"10V"
PACKAGE"0402"
TOLERANCE"10%"
CDS_LIB"passive"
CDS_LMAN_SYM_OUTLINE"-50,0,50,-50"
CLS_PN"G105-0B104-CK"
$LOCATION"C222"
CDS_LOCATION"C222"
$SEC"1"
CDS_SEC"1";
"2"
$PN"2"1;
"1"
$PN"1"17;
%"CAPACITOR"
"2","(-9450,5700)","0","passive","I186";
;
VALUE"0.1UF"
PACKAGE"0402"
VOLTAGE"10V"
TOLERANCE"10%"
CDS_LIB"passive"
CDS_LMAN_SYM_OUTLINE"-50,0,50,-50"
CLS_PN"G105-0B104-CK"
$LOCATION"C109"
CDS_LOCATION"C109"
$SEC"1"
CDS_SEC"1";
"2"
$PN"2"1;
"1"
$PN"1"17;
%"CAPACITOR"
"2","(-9100,5700)","0","passive","I187";
;
VALUE"0.1UF"
PACKAGE"0402"
VOLTAGE"10V"
TOLERANCE"10%"
CDS_LIB"passive"
CDS_LMAN_SYM_OUTLINE"-50,0,50,-50"
CLS_PN"G105-0B104-CK"
$LOCATION"C114"
CDS_LOCATION"C114"
$SEC"1"
CDS_SEC"1";
"2"
$PN"2"1;
"1"
$PN"1"17;
%"CAPACITOR"
"2","(-8750,5700)","0","passive","I188";
;
VALUE"0.1UF"
VOLTAGE"10V"
PACKAGE"0402"
TOLERANCE"10%"
CDS_LIB"passive"
CDS_LMAN_SYM_OUTLINE"-50,0,50,-50"
CLS_PN"G105-0B104-CK"
$LOCATION"C121"
CDS_LOCATION"C121"
$SEC"1"
CDS_SEC"1";
"2"
$PN"2"1;
"1"
$PN"1"17;
%"CAPACITOR"
"2","(-8350,5700)","0","passive","I189";
;
VALUE"0.1UF"
VOLTAGE"10V"
PACKAGE"0402"
TOLERANCE"10%"
CDS_LIB"passive"
CDS_LMAN_SYM_OUTLINE"-50,0,50,-50"
CLS_PN"G105-0B104-CK"
$LOCATION"C129"
CDS_LOCATION"C129"
$SEC"1"
CDS_SEC"1";
"2"
$PN"2"1;
"1"
$PN"1"17;
%"CAPACITOR"
"2","(-8000,5700)","0","passive","I190";
;
VALUE"0.1UF"
VOLTAGE"10V"
PACKAGE"0402"
TOLERANCE"10%"
CDS_LMAN_SYM_OUTLINE"-50,0,50,-50"
CDS_LIB"passive"
CLS_PN"G105-0B104-CK"
$LOCATION"C133"
CDS_LOCATION"C133"
$SEC"1"
CDS_SEC"1";
"2"
$PN"2"1;
"1"
$PN"1"17;
%"CAPACITOR"
"2","(-7600,5700)","0","passive","I191";
;
VALUE"0.1UF"
VOLTAGE"10V"
PACKAGE"0402"
TOLERANCE"10%"
CDS_LMAN_SYM_OUTLINE"-50,0,50,-50"
CDS_LIB"passive"
CLS_PN"G105-0B104-CK"
$LOCATION"C141"
CDS_LOCATION"C141"
$SEC"1"
CDS_SEC"1";
"2"
$PN"2"1;
"1"
$PN"1"17;
%"CAPACITOR"
"2","(-7200,5700)","0","passive","I192";
;
VALUE"0.1UF"
VOLTAGE"10V"
PACKAGE"0402"
TOLERANCE"10%"
CLS_PN"G105-0B104-CK"
CDS_LIB"passive"
CDS_LMAN_SYM_OUTLINE"-50,0,50,-50"
$LOCATION"C147"
CDS_LOCATION"C147"
$SEC"1"
CDS_SEC"1";
"2"
$PN"2"1;
"1"
$PN"1"17;
%"CAPACITOR"
"2","(-6850,5700)","0","passive","I193";
;
VALUE"0.1UF"
VOLTAGE"10V"
PACKAGE"0402"
TOLERANCE"10%"
CDS_LMAN_SYM_OUTLINE"-50,0,50,-50"
CDS_LIB"passive"
CLS_PN"G105-0B104-CK"
$LOCATION"C152"
CDS_LOCATION"C152"
$SEC"1"
CDS_SEC"1";
"2"
$PN"2"1;
"1"
$PN"1"17;
%"CAPACITOR"
"2","(-6500,5700)","0","passive","I194";
;
PACKAGE"0402"
VALUE"0.1UF"
VOLTAGE"10V"
TOLERANCE"10%"
CDS_LMAN_SYM_OUTLINE"-50,0,50,-50"
CDS_LIB"passive"
CLS_PN"G105-0B104-CK"
$LOCATION"C156"
CDS_LOCATION"C156"
$SEC"1"
CDS_SEC"1";
"2"
$PN"2"1;
"1"
$PN"1"17;
%"CAPACITOR"
"2","(-6150,5700)","0","passive","I195";
;
PACKAGE"0402"
VALUE"0.1UF"
VOLTAGE"10V"
TOLERANCE"10%"
CDS_LMAN_SYM_OUTLINE"-50,0,50,-50"
CDS_LIB"passive"
CLS_PN"G105-0B104-CK"
$LOCATION"C161"
CDS_LOCATION"C161"
$SEC"1"
CDS_SEC"1";
"2"
$PN"2"1;
"1"
$PN"1"17;
%"CAPACITOR"
"2","(-5750,5700)","0","passive","I196";
;
VALUE"0.1UF"
VOLTAGE"10V"
PACKAGE"0402"
TOLERANCE"10%"
CDS_LMAN_SYM_OUTLINE"-50,0,50,-50"
CDS_LIB"passive"
CLS_PN"G105-0B104-CK"
$LOCATION"C166"
CDS_LOCATION"C166"
$SEC"1"
CDS_SEC"1";
"2"
$PN"2"1;
"1"
$PN"1"17;
%"CAPACITOR"
"2","(-5400,5700)","0","passive","I197";
;
VALUE"0.1UF"
VOLTAGE"10V"
PACKAGE"0402"
TOLERANCE"10%"
CDS_LMAN_SYM_OUTLINE"-50,0,50,-50"
CDS_LIB"passive"
CLS_PN"G105-0B104-CK"
$LOCATION"C169"
CDS_LOCATION"C169"
$SEC"1"
CDS_SEC"1";
"2"
$PN"2"1;
"1"
$PN"1"17;
%"CAPACITOR"
"2","(-5000,5700)","0","passive","I198";
;
VALUE"0.1UF"
VOLTAGE"10V"
PACKAGE"0402"
TOLERANCE"10%"
CDS_LIB"passive"
CDS_LMAN_SYM_OUTLINE"-50,0,50,-50"
CLS_PN"G105-0B104-CK"
$LOCATION"C171"
CDS_LOCATION"C171"
$SEC"1"
CDS_SEC"1";
"2"
$PN"2"1;
"1"
$PN"1"17;
%"CAPACITOR"
"2","(-10950,7150)","0","passive","I199";
;
VALUE"0.1UF"
VOLTAGE"10V"
PACKAGE"0402"
TOLERANCE"10%"
CDS_LMAN_SYM_OUTLINE"-50,0,50,-50"
CDS_LIB"passive"
CLS_PN"G105-0B104-CK"
$LOCATION"C200"
CDS_LOCATION"C200"
$SEC"1"
CDS_SEC"1";
"2"
$PN"2"2;
"1"
$PN"1"18;
%"CAPACITOR"
"2","(-10600,7150)","0","passive","I200";
;
VALUE"0.1UF"
VOLTAGE"10V"
PACKAGE"0402"
TOLERANCE"10%"
CDS_LMAN_SYM_OUTLINE"-50,0,50,-50"
CDS_LIB"passive"
CLS_PN"G105-0B104-CK"
$LOCATION"C206"
CDS_LOCATION"C206"
$SEC"1"
CDS_SEC"1";
"2"
$PN"2"2;
"1"
$PN"1"18;
%"CAPACITOR"
"2","(-10250,7150)","0","passive","I201";
;
VALUE"0.1UF"
VOLTAGE"10V"
PACKAGE"0402"
TOLERANCE"10%"
CDS_LMAN_SYM_OUTLINE"-50,0,50,-50"
CDS_LIB"passive"
CLS_PN"G105-0B104-CK"
$LOCATION"C212"
CDS_LOCATION"C212"
$SEC"1"
CDS_SEC"1";
"2"
$PN"2"2;
"1"
$PN"1"18;
%"CAPACITOR"
"2","(-9900,7150)","0","passive","I202";
;
VALUE"0.1UF"
VOLTAGE"10V"
PACKAGE"0402"
TOLERANCE"10%"
CDS_LMAN_SYM_OUTLINE"-50,0,50,-50"
CDS_LIB"passive"
CLS_PN"G105-0B104-CK"
$LOCATION"C219"
CDS_LOCATION"C219"
$SEC"1"
CDS_SEC"1";
"2"
$PN"2"2;
"1"
$PN"1"18;
%"CAPACITOR"
"2","(-9500,7150)","0","passive","I203";
;
VALUE"0.1UF"
VOLTAGE"10V"
PACKAGE"0402"
TOLERANCE"10%"
CDS_LMAN_SYM_OUTLINE"-50,0,50,-50"
CDS_LIB"passive"
CLS_PN"G105-0B104-CK"
$LOCATION"C106"
CDS_LOCATION"C106"
$SEC"1"
CDS_SEC"1";
"2"
$PN"2"2;
"1"
$PN"1"18;
%"CAPACITOR"
"2","(-9100,7150)","0","passive","I204";
;
VALUE"0.1UF"
VOLTAGE"10V"
PACKAGE"0402"
TOLERANCE"10%"
CLS_PN"G105-0B104-CK"
CDS_LMAN_SYM_OUTLINE"-50,0,50,-50"
CDS_LIB"passive"
$LOCATION"C113"
CDS_LOCATION"C113"
$SEC"1"
CDS_SEC"1";
"2"
$PN"2"2;
"1"
$PN"1"18;
%"CAPACITOR"
"2","(-10950,4300)","0","passive","I205";
;
VALUE"0.1UF"
VOLTAGE"10V"
PACKAGE"0402"
TOLERANCE"10%"
CDS_LMAN_SYM_OUTLINE"-50,0,50,-50"
CDS_LIB"passive"
CLS_PN"G105-0B104-CK"
$LOCATION"C202"
CDS_LOCATION"C202"
$SEC"1"
CDS_SEC"1";
"2"
$PN"2"3;
"1"
$PN"1"11;
%"CAPACITOR"
"2","(-10550,4300)","0","passive","I206";
;
VALUE"0.1UF"
VOLTAGE"10V"
PACKAGE"0402"
TOLERANCE"10%"
CDS_LMAN_SYM_OUTLINE"-50,0,50,-50"
CDS_LIB"passive"
CLS_PN"G105-0B104-CK"
$LOCATION"C210"
CDS_LOCATION"C210"
$SEC"1"
CDS_SEC"1";
"2"
$PN"2"3;
"1"
$PN"1"11;
%"CAPACITOR"
"2","(-10200,4300)","0","passive","I207";
;
VOLTAGE"10V"
VALUE"0.1UF"
PACKAGE"0402"
TOLERANCE"10%"
CDS_LMAN_SYM_OUTLINE"-50,0,50,-50"
CDS_LIB"passive"
CLS_PN"G105-0B104-CK"
$LOCATION"C215"
CDS_LOCATION"C215"
$SEC"1"
CDS_SEC"1";
"2"
$PN"2"3;
"1"
$PN"1"11;
%"CAPACITOR"
"2","(-9800,4300)","0","passive","I208";
;
VALUE"0.1UF"
VOLTAGE"10V"
PACKAGE"0402"
TOLERANCE"10%"
CDS_LIB"passive"
CDS_LMAN_SYM_OUTLINE"-50,0,50,-50"
CLS_PN"G105-0B104-CK"
$LOCATION"C103"
CDS_LOCATION"C103"
$SEC"1"
CDS_SEC"1";
"2"
$PN"2"3;
"1"
$PN"1"11;
%"CAPACITOR"
"2","(-9350,4300)","0","passive","I209";
;
VOLTAGE"10V"
PACKAGE"0402"
VALUE"0.1UF"
TOLERANCE"10%"
CLS_PN"G105-0B104-CK"
CDS_LMAN_SYM_OUTLINE"-50,0,50,-50"
CDS_LIB"passive"
$LOCATION"C112"
CDS_LOCATION"C112"
$SEC"1"
CDS_SEC"1";
"2"
$PN"2"3;
"1"
$PN"1"11;
%"CAPACITOR"
"2","(-8950,4300)","0","passive","I210";
;
VALUE"0.1UF"
VOLTAGE"10V"
PACKAGE"0402"
TOLERANCE"10%"
CLS_PN"G105-0B104-CK"
CDS_LMAN_SYM_OUTLINE"-50,0,50,-50"
CDS_LIB"passive"
$LOCATION"C119"
CDS_LOCATION"C119"
$SEC"1"
CDS_SEC"1";
"2"
$PN"2"3;
"1"
$PN"1"11;
%"CAPACITOR"
"2","(-8600,4300)","0","passive","I211";
;
VALUE"0.1UF"
VOLTAGE"10V"
PACKAGE"0402"
TOLERANCE"10%"
CLS_PN"G105-0B104-CK"
CDS_LMAN_SYM_OUTLINE"-50,0,50,-50"
CDS_LIB"passive"
$LOCATION"C126"
CDS_LOCATION"C126"
$SEC"1"
CDS_SEC"1";
"2"
$PN"2"3;
"1"
$PN"1"11;
%"CAPACITOR"
"2","(-8250,4300)","0","passive","I212";
;
VOLTAGE"10V"
PACKAGE"0402"
VALUE"0.1UF"
TOLERANCE"10%"
CLS_PN"G105-0B104-CK"
CDS_LMAN_SYM_OUTLINE"-50,0,50,-50"
CDS_LIB"passive"
$LOCATION"C132"
CDS_LOCATION"C132"
$SEC"1"
CDS_SEC"1";
"2"
$PN"2"3;
"1"
$PN"1"11;
%"CAPACITOR"
"2","(-7900,4300)","0","passive","I213";
;
VOLTAGE"10V"
PACKAGE"0402"
VALUE"0.1UF"
TOLERANCE"10%"
CLS_PN"G105-0B104-CK"
CDS_LMAN_SYM_OUTLINE"-50,0,50,-50"
CDS_LIB"passive"
$LOCATION"C139"
CDS_LOCATION"C139"
$SEC"1"
CDS_SEC"1";
"2"
$PN"2"3;
"1"
$PN"1"11;
%"CAPACITOR"
"2","(-7500,4300)","0","passive","I214";
;
VALUE"0.1UF"
VOLTAGE"10V"
PACKAGE"0402"
TOLERANCE"10%"
CLS_PN"G105-0B104-CK"
CDS_LMAN_SYM_OUTLINE"-50,0,50,-50"
CDS_LIB"passive"
$LOCATION"C144"
CDS_LOCATION"C144"
$SEC"1"
CDS_SEC"1";
"2"
$PN"2"3;
"1"
$PN"1"11;
%"CAPACITOR"
"2","(-7150,4300)","0","passive","I215";
;
VOLTAGE"10V"
PACKAGE"0402"
VALUE"0.1UF"
TOLERANCE"10%"
CLS_PN"G105-0B104-CK"
CDS_LMAN_SYM_OUTLINE"-50,0,50,-50"
CDS_LIB"passive"
$LOCATION"C149"
CDS_LOCATION"C149"
$SEC"1"
CDS_SEC"1";
"2"
$PN"2"3;
"1"
$PN"1"11;
%"CAPACITOR"
"2","(-10950,3450)","0","passive","I216";
;
VALUE"0.1UF"
VOLTAGE"10V"
PACKAGE"0402"
TOLERANCE"10%"
CLS_PN"G105-0B104-CK"
CDS_LMAN_SYM_OUTLINE"-50,0,50,-50"
CDS_LIB"passive"
$LOCATION"C203"
CDS_LOCATION"C203"
$SEC"1"
CDS_SEC"1";
"2"
$PN"2"14;
"1"
$PN"1"11;
%"CAPACITOR"
"2","(-10550,3450)","0","passive","I217";
;
VALUE"0.1UF"
VOLTAGE"10V"
PACKAGE"0402"
TOLERANCE"10%"
CLS_PN"G105-0B104-CK"
CDS_LMAN_SYM_OUTLINE"-50,0,50,-50"
CDS_LIB"passive"
$LOCATION"C211"
CDS_LOCATION"C211"
$SEC"1"
CDS_SEC"1";
"2"
$PN"2"14;
"1"
$PN"1"11;
%"CAPACITOR"
"2","(-10200,3450)","0","passive","I218";
;
VOLTAGE"10V"
VALUE"0.1UF"
PACKAGE"0402"
TOLERANCE"10%"
CLS_PN"G105-0B104-CK"
CDS_LMAN_SYM_OUTLINE"-50,0,50,-50"
CDS_LIB"passive"
$LOCATION"C216"
CDS_LOCATION"C216"
$SEC"1"
CDS_SEC"1";
"2"
$PN"2"14;
"1"
$PN"1"11;
%"CAPACITOR"
"2","(-9850,3450)","0","passive","I219";
;
PACKAGE"0402"
VOLTAGE"10V"
VALUE"0.1UF"
TOLERANCE"10%"
CLS_PN"G105-0B104-CK"
CDS_LMAN_SYM_OUTLINE"-50,0,50,-50"
CDS_LIB"passive"
$LOCATION"C221"
CDS_LOCATION"C221"
$SEC"1"
CDS_SEC"1";
"2"
$PN"2"14;
"1"
$PN"1"11;
%"CAPACITOR"
"2","(-9500,3450)","0","passive","I220";
;
VOLTAGE"10V"
PACKAGE"0402"
VALUE"0.1UF"
TOLERANCE"10%"
CLS_PN"G105-0B104-CK"
CDS_LMAN_SYM_OUTLINE"-50,0,50,-50"
CDS_LIB"passive"
$LOCATION"C107"
CDS_LOCATION"C107"
$SEC"1"
CDS_SEC"1";
"2"
$PN"2"14;
"1"
$PN"1"11;
%"CAPACITOR"
"2","(-9100,3450)","0","passive","I221";
;
VOLTAGE"10V"
PACKAGE"0402"
VALUE"0.1UF"
TOLERANCE"10%"
CLS_PN"G105-0B104-CK"
CDS_LMAN_SYM_OUTLINE"-50,0,50,-50"
CDS_LIB"passive"
$LOCATION"C115"
CDS_LOCATION"C115"
$SEC"1"
CDS_SEC"1";
"2"
$PN"2"14;
"1"
$PN"1"11;
%"CAPACITOR"
"2","(-8700,3450)","0","passive","I222";
;
PACKAGE"0402"
VOLTAGE"10V"
VALUE"0.1UF"
TOLERANCE"10%"
CLS_PN"G105-0B104-CK"
CDS_LMAN_SYM_OUTLINE"-50,0,50,-50"
CDS_LIB"passive"
$LOCATION"C223"
CDS_LOCATION"C223"
$SEC"1"
CDS_SEC"1";
"2"
$PN"2"14;
"1"
$PN"1"11;
%"CAPACITOR"
"2","(-8350,3450)","0","passive","I223";
;
PACKAGE"0402"
VOLTAGE"10V"
VALUE"0.1UF"
TOLERANCE"10%"
CLS_PN"G105-0B104-CK"
CDS_LMAN_SYM_OUTLINE"-50,0,50,-50"
CDS_LIB"passive"
$LOCATION"C130"
CDS_LOCATION"C130"
$SEC"1"
CDS_SEC"1";
"2"
$PN"2"14;
"1"
$PN"1"11;
%"CAPACITOR"
"2","(-8000,3450)","0","passive","I224";
;
PACKAGE"0402"
VALUE"0.1UF"
VOLTAGE"10V"
TOLERANCE"10%"
CLS_PN"G105-0B104-CK"
CDS_LMAN_SYM_OUTLINE"-50,0,50,-50"
CDS_LIB"passive"
$LOCATION"C134"
CDS_LOCATION"C134"
$SEC"1"
CDS_SEC"1";
"2"
$PN"2"14;
"1"
$PN"1"11;
%"CAPACITOR"
"2","(-7650,3450)","0","passive","I225";
;
VALUE"0.1UF"
VOLTAGE"10V"
PACKAGE"0402"
TOLERANCE"10%"
CLS_PN"G105-0B104-CK"
CDS_LMAN_SYM_OUTLINE"-50,0,50,-50"
CDS_LIB"passive"
$LOCATION"C140"
CDS_LOCATION"C140"
$SEC"1"
CDS_SEC"1";
"2"
$PN"2"14;
"1"
$PN"1"11;
%"CAPACITOR"
"2","(-7250,3450)","0","passive","I226";
;
VALUE"0.1UF"
VOLTAGE"10V"
PACKAGE"0402"
TOLERANCE"10%"
CLS_PN"G105-0B104-CK"
CDS_LMAN_SYM_OUTLINE"-50,0,50,-50"
CDS_LIB"passive"
$LOCATION"C145"
CDS_LOCATION"C145"
$SEC"1"
CDS_SEC"1";
"2"
$PN"2"14;
"1"
$PN"1"11;
%"CAPACITOR"
"2","(-6850,3450)","0","passive","I227";
;
VALUE"0.1UF"
VOLTAGE"10V"
PACKAGE"0402"
TOLERANCE"10%"
CLS_PN"G105-0B104-CK"
CDS_LMAN_SYM_OUTLINE"-50,0,50,-50"
CDS_LIB"passive"
$LOCATION"C153"
CDS_LOCATION"C153"
$SEC"1"
CDS_SEC"1";
"2"
$PN"2"14;
"1"
$PN"1"11;
%"CAPACITOR"
"2","(-6500,3450)","0","passive","I228";
;
VALUE"0.1UF"
VOLTAGE"10V"
PACKAGE"0402"
TOLERANCE"10%"
CLS_PN"G105-0B104-CK"
CDS_LMAN_SYM_OUTLINE"-50,0,50,-50"
CDS_LIB"passive"
$LOCATION"C157"
CDS_LOCATION"C157"
$SEC"1"
CDS_SEC"1";
"2"
$PN"2"14;
"1"
$PN"1"11;
%"CAPACITOR"
"2","(-6150,3450)","0","passive","I229";
;
VOLTAGE"10V"
VALUE"0.1UF"
PACKAGE"0402"
TOLERANCE"10%"
CLS_PN"G105-0B104-CK"
CDS_LMAN_SYM_OUTLINE"-50,0,50,-50"
CDS_LIB"passive"
$LOCATION"C162"
CDS_LOCATION"C162"
$SEC"1"
CDS_SEC"1";
"2"
$PN"2"14;
"1"
$PN"1"11;
%"CAPACITOR"
"2","(-5800,3450)","0","passive","I230";
;
VOLTAGE"10V"
VALUE"0.1UF"
PACKAGE"0402"
TOLERANCE"10%"
CLS_PN"G105-0B104-CK"
CDS_LMAN_SYM_OUTLINE"-50,0,50,-50"
CDS_LIB"passive"
$LOCATION"C165"
CDS_LOCATION"C165"
$SEC"1"
CDS_SEC"1";
"2"
$PN"2"14;
"1"
$PN"1"11;
%"CAPACITOR"
"2","(-10950,2050)","0","passive","I231";
;
VOLTAGE"10V"
PACKAGE"0402"
VALUE"0.1UF"
TOLERANCE"10%"
CDS_LMAN_SYM_OUTLINE"-50,0,50,-50"
CDS_LIB"passive"
CLS_PN"G105-0B104-CK"
$LOCATION"C204"
CDS_LOCATION"C204"
$SEC"1"
CDS_SEC"1";
"2"
$PN"2"5;
"1"
$PN"1"6;
%"CAPACITOR"
"2","(-10600,2050)","0","passive","I232";
;
VOLTAGE"10V"
PACKAGE"0402"
VALUE"0.1UF"
TOLERANCE"10%"
CLS_PN"G105-0B104-CK"
CDS_LMAN_SYM_OUTLINE"-50,0,50,-50"
CDS_LIB"passive"
$LOCATION"C208"
CDS_LOCATION"C208"
$SEC"1"
CDS_SEC"1";
"2"
$PN"2"5;
"1"
$PN"1"6;
%"CAPACITOR"
"2","(-10250,2050)","0","passive","I233";
;
VALUE"0.1UF"
PACKAGE"0402"
VOLTAGE"10V"
TOLERANCE"10%"
CLS_PN"G105-0B104-CK"
CDS_LMAN_SYM_OUTLINE"-50,0,50,-50"
CDS_LIB"passive"
$LOCATION"C213"
CDS_LOCATION"C213"
$SEC"1"
CDS_SEC"1";
"2"
$PN"2"5;
"1"
$PN"1"6;
%"CAPACITOR"
"2","(-9900,2050)","0","passive","I234";
;
VOLTAGE"10V"
VALUE"0.1UF"
PACKAGE"0402"
TOLERANCE"10%"
CLS_PN"G105-0B104-CK"
CDS_LMAN_SYM_OUTLINE"-50,0,50,-50"
CDS_LIB"passive"
$LOCATION"C220"
CDS_LOCATION"C220"
$SEC"1"
CDS_SEC"1";
"2"
$PN"2"5;
"1"
$PN"1"6;
%"CAPACITOR"
"2","(-9500,2050)","0","passive","I235";
;
VALUE"0.1UF"
VOLTAGE"10V"
PACKAGE"0402"
TOLERANCE"10%"
CLS_PN"G105-0B104-CK"
CDS_LMAN_SYM_OUTLINE"-50,0,50,-50"
CDS_LIB"passive"
$LOCATION"C108"
CDS_LOCATION"C108"
$SEC"1"
CDS_SEC"1";
"2"
$PN"2"5;
"1"
$PN"1"6;
%"CAPACITOR"
"2","(-9100,2050)","0","passive","I236";
;
VALUE"0.1UF"
VOLTAGE"10V"
PACKAGE"0402"
TOLERANCE"10%"
CLS_PN"G105-0B104-CK"
CDS_LMAN_SYM_OUTLINE"-50,0,50,-50"
CDS_LIB"passive"
$LOCATION"C116"
CDS_LOCATION"C116"
$SEC"1"
CDS_SEC"1";
"2"
$PN"2"5;
"1"
$PN"1"6;
%"CAPACITOR"
"2","(-8750,2050)","0","passive","I237";
;
VOLTAGE"10V"
VALUE"0.1UF"
PACKAGE"0402"
TOLERANCE"10%"
CLS_PN"G105-0B104-CK"
CDS_LMAN_SYM_OUTLINE"-50,0,50,-50"
CDS_LIB"passive"
$LOCATION"C122"
CDS_LOCATION"C122"
$SEC"1"
CDS_SEC"1";
"2"
$PN"2"5;
"1"
$PN"1"6;
%"CAPACITOR"
"2","(-8400,2050)","0","passive","I238";
;
VALUE"0.1UF"
PACKAGE"0402"
VOLTAGE"10V"
TOLERANCE"10%"
CLS_PN"G105-0B104-CK"
CDS_LMAN_SYM_OUTLINE"-50,0,50,-50"
CDS_LIB"passive"
$LOCATION"C127"
CDS_LOCATION"C127"
$SEC"1"
CDS_SEC"1";
"2"
$PN"2"5;
"1"
$PN"1"6;
%"CAPACITOR"
"2","(-8000,2050)","0","passive","I239";
;
VOLTAGE"10V"
VALUE"0.1UF"
PACKAGE"0402"
TOLERANCE"10%"
CLS_PN"G105-0B104-CK"
CDS_LMAN_SYM_OUTLINE"-50,0,50,-50"
CDS_LIB"passive"
$LOCATION"C135"
CDS_LOCATION"C135"
$SEC"1"
CDS_SEC"1";
"2"
$PN"2"5;
"1"
$PN"1"6;
%"CAPACITOR"
"2","(-7600,2050)","0","passive","I240";
;
PACKAGE"0402"
VALUE"0.1UF"
VOLTAGE"10V"
TOLERANCE"10%"
CLS_PN"G105-0B104-CK"
CDS_LMAN_SYM_OUTLINE"-50,0,50,-50"
CDS_LIB"passive"
$LOCATION"C142"
CDS_LOCATION"C142"
$SEC"1"
CDS_SEC"1";
"2"
$PN"2"5;
"1"
$PN"1"6;
%"CAPACITOR"
"2","(-7250,2050)","0","passive","I241";
;
VALUE"0.1UF"
PACKAGE"0402"
VOLTAGE"10V"
TOLERANCE"10%"
CDS_LMAN_SYM_OUTLINE"-50,0,50,-50"
CDS_LIB"passive"
CLS_PN"G105-0B104-CK"
$LOCATION"C146"
CDS_LOCATION"C146"
$SEC"1"
CDS_SEC"1";
"2"
$PN"2"5;
"1"
$PN"1"6;
%"CAPACITOR"
"2","(-6900,2050)","0","passive","I242";
;
VALUE"0.1UF"
PACKAGE"0402"
VOLTAGE"10V"
CLS_PN"G105-0B104-CK"
CDS_LMAN_SYM_OUTLINE"-50,0,50,-50"
CDS_LIB"passive"
TOLERANCE"10%"
$LOCATION"C151"
CDS_LOCATION"C151"
$SEC"1"
CDS_SEC"1";
"2"
$PN"2"5;
"1"
$PN"1"6;
%"CAPACITOR"
"2","(-8350,7150)","0","passive","I243";
;
VALUE"4.7UF"
VOLTAGE"6.3V"
PACKAGE"0402"
TOLERANCE"20%"
CLS_PN"G105-0F475-BM"
CDS_LIB"passive"
CDS_LMAN_SYM_OUTLINE"-50,0,50,-50"
$LOCATION"C128"
CDS_LOCATION"C128"
$SEC"1"
CDS_SEC"1";
"2"
$PN"2"2;
"1"
$PN"1"18;
%"CAPACITOR"
"2","(-6450,2050)","0","passive","I245";
;
PACKAGE"0402"
VALUE"4.7UF"
VOLTAGE"6.3V"
CLS_PN"G105-0F475-BM"
CDS_LIB"passive"
CDS_LMAN_SYM_OUTLINE"-50,0,50,-50"
TOLERANCE"20%"
$LOCATION"C160"
CDS_LOCATION"C160"
$SEC"1"
CDS_SEC"1";
"2"
$PN"2"5;
"1"
$PN"1"6;
%"CAPACITOR"
"2","(-9100,-650)","0","passive","I246";
;
VALUE"4.7UF"
VOLTAGE"6.3V"
PACKAGE"0402"
TOLERANCE"20%"
CLS_PN"G105-0F475-BM"
CDS_LMAN_SYM_OUTLINE"-50,0,50,-50"
CDS_LIB"passive"
$LOCATION"C117"
CDS_LOCATION"C117"
$SEC"1"
CDS_SEC"1";
"2"
$PN"2"15;
"1"
$PN"1"13;
%"CAPACITOR"
"2","(-8350,450)","0","passive","I248";
;
PACKAGE"0402"
VOLTAGE"6.3V"
VALUE"4.7UF"
TOLERANCE"20%"
CLS_PN"G105-0F475-BM"
CDS_LMAN_SYM_OUTLINE"-50,0,50,-50"
CDS_LIB"passive"
$LOCATION"C131"
CDS_LOCATION"C131"
$SEC"1"
CDS_SEC"1";
"2"
$PN"2"4;
"1"
$PN"1"16;
%"CAPACITOR"
"2","(-8000,-650)","0","passive","I249";
;
PACKAGE"0402"
VALUE"0.1UF"
VOLTAGE"10V"
TOLERANCE"10%"
CLS_PN"G105-0B104-CK"
CDS_LMAN_SYM_OUTLINE"-50,0,50,-50"
CDS_LIB"passive"
$LOCATION"C136"
CDS_LOCATION"C136"
$SEC"1"
CDS_SEC"1";
"2"
$PN"2"15;
"1"
$PN"1"8;
%"CAPACITOR"
"2","(-7200,450)","0","passive","I250";
;
VALUE"0.1UF"
PACKAGE"0402"
VOLTAGE"10V"
TOLERANCE"10%"
CDS_LIB"passive"
CDS_LMAN_SYM_OUTLINE"-50,0,50,-50"
CLS_PN"G105-0B104-CK"
$LOCATION"C148"
CDS_LOCATION"C148"
$SEC"1"
CDS_SEC"1";
"2"
$PN"2"4;
"1"
$PN"1"9;
%"CAPACITOR"
"2","(-10150,450)","0","passive","I251";
;
VOLTAGE"10V"
PACKAGE"0402"
VALUE"0.1UF"
CLS_PN"G105-0B104-CK"
CDS_LIB"passive"
CDS_LMAN_SYM_OUTLINE"-50,0,50,-50"
TOLERANCE"10%"
$LOCATION"C218"
CDS_LOCATION"C218"
$SEC"1"
CDS_SEC"1";
"2"
$PN"2"4;
"1"
$PN"1"16;
%"CAPACITOR"
"2","(-9750,450)","0","passive","I252";
;
PACKAGE"0402"
VOLTAGE"10V"
VALUE"0.1UF"
TOLERANCE"10%"
CDS_LMAN_SYM_OUTLINE"-50,0,50,-50"
CDS_LIB"passive"
CLS_PN"G105-0B104-CK"
$LOCATION"C105"
CDS_LOCATION"C105"
$SEC"1"
CDS_SEC"1";
"2"
$PN"2"4;
"1"
$PN"1"16;
%"CAPACITOR"
"2","(-9400,450)","0","passive","I253";
;
PACKAGE"0402"
VALUE"0.1UF"
VOLTAGE"10V"
TOLERANCE"10%"
CLS_PN"G105-0B104-CK"
CDS_LMAN_SYM_OUTLINE"-50,0,50,-50"
CDS_LIB"passive"
$LOCATION"C111"
CDS_LOCATION"C111"
$SEC"1"
CDS_SEC"1";
"2"
$PN"2"4;
"1"
$PN"1"16;
%"CAPACITOR"
"2","(-9050,450)","0","passive","I254";
;
VALUE"0.1UF"
VOLTAGE"10V"
PACKAGE"0402"
TOLERANCE"10%"
CLS_PN"G105-0B104-CK"
CDS_LMAN_SYM_OUTLINE"-50,0,50,-50"
CDS_LIB"passive"
$LOCATION"C118"
CDS_LOCATION"C118"
$SEC"1"
CDS_SEC"1";
"2"
$PN"2"4;
"1"
$PN"1"16;
%"CAPACITOR"
"2","(-8700,450)","0","passive","I255";
;
VALUE"0.1UF"
VOLTAGE"10V"
PACKAGE"0402"
TOLERANCE"10%"
CLS_PN"G105-0B104-CK"
CDS_LMAN_SYM_OUTLINE"-50,0,50,-50"
CDS_LIB"passive"
$LOCATION"C124"
CDS_LOCATION"C124"
$SEC"1"
CDS_SEC"1";
"2"
$PN"2"4;
"1"
$PN"1"16;
%"CAPACITOR"
"2","(-9450,-650)","0","passive","I256";
;
VALUE"0.1UF"
VOLTAGE"10V"
PACKAGE"0402"
TOLERANCE"10%"
CLS_PN"G105-0B104-CK"
CDS_LMAN_SYM_OUTLINE"-50,0,50,-50"
CDS_LIB"passive"
$LOCATION"C110"
CDS_LOCATION"C110"
$SEC"1"
CDS_SEC"1";
"2"
$PN"2"15;
"1"
$PN"1"13;
%"CAPACITOR"
"2","(-9800,-650)","0","passive","I257";
;
VOLTAGE"10V"
PACKAGE"0402"
VALUE"0.1UF"
TOLERANCE"10%"
CLS_PN"G105-0B104-CK"
CDS_LMAN_SYM_OUTLINE"-50,0,50,-50"
CDS_LIB"passive"
$LOCATION"C104"
CDS_LOCATION"C104"
$SEC"1"
CDS_SEC"1";
"2"
$PN"2"15;
"1"
$PN"1"13;
%"CAPACITOR"
"2","(-10200,-650)","0","passive","I258";
;
VOLTAGE"10V"
PACKAGE"0402"
VALUE"0.1UF"
TOLERANCE"10%"
CLS_PN"G105-0B104-CK"
CDS_LMAN_SYM_OUTLINE"-50,0,50,-50"
CDS_LIB"passive"
$LOCATION"C217"
CDS_LOCATION"C217"
$SEC"1"
CDS_SEC"1";
"2"
$PN"2"15;
"1"
$PN"1"13;
%"CAPACITOR"
"2","(-10600,-650)","0","passive","I259";
;
VALUE"0.1UF"
VOLTAGE"10V"
PACKAGE"0402"
TOLERANCE"10%"
CLS_PN"G105-0B104-CK"
CDS_LMAN_SYM_OUTLINE"-50,0,50,-50"
CDS_LIB"passive"
$LOCATION"C209"
CDS_LOCATION"C209"
$SEC"1"
CDS_SEC"1";
"2"
$PN"2"15;
"1"
$PN"1"13;
%"CAPACITOR"
"2","(-10950,-650)","0","passive","I260";
;
VALUE"0.1UF"
VOLTAGE"10V"
PACKAGE"0402"
TOLERANCE"10%"
CLS_PN"G105-0B104-CK"
CDS_LMAN_SYM_OUTLINE"-50,0,50,-50"
CDS_LIB"passive"
$LOCATION"C205"
CDS_LOCATION"C205"
$SEC"1"
CDS_SEC"1";
"2"
$PN"2"15;
"1"
$PN"1"13;
%"CAPACITOR"
"2","(-8650,-650)","0","passive","I264";
;
VALUE"47UF"
VOLTAGE"4V"
PACKAGE"0805"
TOLERANCE"20%"
CDS_LMAN_SYM_OUTLINE"-50,0,50,-50"
CDS_LIB"passive"
CLS_PN"G107-0F476-AM"
$LOCATION"C125"
CDS_LOCATION"C125"
$SEC"1"
CDS_SEC"1";
"2"
$PN"2"15;
"1"
$PN"1"13;
%"CAPACITOR"
"2","(-7550,-650)","0","passive","I265";
;
PACKAGE"0805"
VOLTAGE"4V"
VALUE"47UF"
CDS_LMAN_SYM_OUTLINE"-50,0,50,-50"
CDS_LIB"passive"
CLS_PN"G107-0F476-AM"
TOLERANCE"20%"
$LOCATION"C143"
CDS_LOCATION"C143"
$SEC"1"
CDS_SEC"1";
"2"
$PN"2"15;
"1"
$PN"1"8;
%"CAPACITOR"
"2","(-6750,450)","0","passive","I266";
;
VOLTAGE"4V"
VALUE"47UF"
PACKAGE"0805"
CLS_PN"G107-0F476-AM"
CDS_LMAN_SYM_OUTLINE"-50,0,50,-50"
CDS_LIB"passive"
TOLERANCE"20%"
$LOCATION"C155"
CDS_LOCATION"C155"
$SEC"1"
CDS_SEC"1";
"2"
$PN"2"4;
"1"
$PN"1"9;
%"CAPACITOR"
"2","(-5350,2050)","0","passive","I267";
;
PACKAGE"0805"
VOLTAGE"10V"
VALUE"22UF"
CLS_PN"G107-0F226-CM"
TOLERANCE"20%"
CDS_LIB"passive"
CDS_LMAN_SYM_OUTLINE"-50,0,50,-50"
$LOCATION"C168"
CDS_LOCATION"C168"
$SEC"1"
CDS_SEC"1";
"2"
$PN"2"5;
"1"
$PN"1"6;
%"CAPACITOR"
"2","(-5700,2050)","0","passive","I268";
;
VALUE"22UF"
PACKAGE"0805"
VOLTAGE"10V"
CLS_PN"G107-0F226-CM"
TOLERANCE"20%"
CDS_LMAN_SYM_OUTLINE"-50,0,50,-50"
CDS_LIB"passive"
$LOCATION"C164"
CDS_LOCATION"C164"
$SEC"1"
CDS_SEC"1";
"2"
$PN"2"5;
"1"
$PN"1"6;
%"CAPACITOR"
"2","(-6750,4300)","0","passive","I270";
;
VALUE"4.7UF"
VOLTAGE"6.3V"
PACKAGE"0402"
CDS_LIB"passive"
CDS_LMAN_SYM_OUTLINE"-50,0,50,-50"
CLS_PN"G105-0F475-BM"
TOLERANCE"20%"
$LOCATION"C154"
CDS_LOCATION"C154"
$SEC"1"
CDS_SEC"1";
"2"
$PN"2"3;
"1"
$PN"1"11;
%"CAPACITOR"
"2","(-6400,4300)","0","passive","I271";
;
VOLTAGE"6.3V"
VALUE"4.7UF"
PACKAGE"0402"
TOLERANCE"20%"
CDS_LIB"passive"
CDS_LMAN_SYM_OUTLINE"-50,0,50,-50"
CLS_PN"G105-0F475-BM"
$LOCATION"C159"
CDS_LOCATION"C159"
$SEC"1"
CDS_SEC"1";
"2"
$PN"2"3;
"1"
$PN"1"11;
%"CAPACITOR"
"2","(-6050,4300)","0","passive","I272";
;
VOLTAGE"6.3V"
VALUE"4.7UF"
PACKAGE"0402"
TOLERANCE"20%"
CDS_LIB"passive"
CDS_LMAN_SYM_OUTLINE"-50,0,50,-50"
CLS_PN"G105-0F475-BM"
$LOCATION"C163"
CDS_LOCATION"C163"
$SEC"1"
CDS_SEC"1";
"2"
$PN"2"3;
"1"
$PN"1"11;
%"CAPACITOR"
"2","(-5700,4300)","0","passive","I273";
;
PACKAGE"0402"
VALUE"4.7UF"
VOLTAGE"6.3V"
TOLERANCE"20%"
CLS_PN"G105-0F475-BM"
CDS_LMAN_SYM_OUTLINE"-50,0,50,-50"
CDS_LIB"passive"
$LOCATION"C167"
CDS_LOCATION"C167"
$SEC"1"
CDS_SEC"1";
"2"
$PN"2"3;
"1"
$PN"1"11;
%"CAPACITOR"
"2","(-2400,5700)","0","passive","I274";
;
VALUE"47UF"
VOLTAGE"4V"
PACKAGE"0805"
CDS_LIB"passive"
CDS_LMAN_SYM_OUTLINE"-50,0,50,-50"
CLS_PN"G107-0F476-AM"
TOLERANCE"20%"
$LOCATION"C179"
CDS_LOCATION"C179"
$SEC"1"
CDS_SEC"1";
"2"
$PN"2"1;
"1"
$PN"1"10;
%"CAPACITOR"
"2","(-7900,7150)","0","passive","I275";
;
VOLTAGE"6.3V"
VALUE"4.7UF"
PACKAGE"0402"
TOLERANCE"20%"
CDS_LIB"passive"
CDS_LMAN_SYM_OUTLINE"-50,0,50,-50"
CLS_PN"G105-0F475-BM"
$LOCATION"C138"
CDS_LOCATION"C138"
$SEC"1"
CDS_SEC"1";
"2"
$PN"2"2;
"1"
$PN"1"18;
%"CAPACITOR"
"2","(-6900,7150)","0","passive","I276";
;
VALUE"0.1UF"
VOLTAGE"10V"
PACKAGE"0402"
TOLERANCE"10%"
CDS_LIB"passive"
CDS_LMAN_SYM_OUTLINE"-50,0,50,-50"
CLS_PN"G105-0B104-CK"
$LOCATION"C150"
CDS_LOCATION"C150"
$SEC"1"
CDS_SEC"1";
"2"
$PN"2"2;
"1"
$PN"1"7;
%"CAPACITOR"
"2","(-3600,5700)","0","passive","I277";
;
VALUE"100UF"
PACKAGE"1210"
VOLTAGE"6.3V"
TOLERANCE"20%"
CLS_PN"G109-0G107-BM"
CDS_LMAN_SYM_OUTLINE"-50,0,50,-50"
CDS_LIB"passive"
$LOCATION"C177"
CDS_LOCATION"C177"
$SEC"1"
CDS_SEC"1";
"2"
$PN"2"1;
"1"
$PN"1"17;
%"CAPACITOR"
"2","(-4650,5700)","0","passive","I280";
;
VALUE"47UF"
PACKAGE"0805"
VOLTAGE"4V"
CLS_PN"G107-0F476-AM"
CDS_LMAN_SYM_OUTLINE"-50,0,50,-50"
CDS_LIB"passive"
TOLERANCE"20%"
$LOCATION"C173"
CDS_LOCATION"C173"
$SEC"1"
CDS_SEC"1";
"2"
$PN"2"1;
"1"
$PN"1"17;
%"CAPACITOR"
"2","(-7950,450)","0","passive","I281";
;
VOLTAGE"4V"
VALUE"47UF"
TOLERANCE"20%"
CLS_PN"G107-0F476-AM"
CDS_LIB"passive"
CDS_LMAN_SYM_OUTLINE"-50,0,50,-50"
$LOCATION"C137"
CDS_LOCATION"C137"
$SEC"1"
CDS_SEC"1";
"2"
$PN"2"4;
"1"
$PN"1"16;
%"CAPACITOR"
"2","(-5350,4300)","0","passive","I282";
;
VALUE"4.7UF"
PACKAGE"0402"
VOLTAGE"6.3V"
TOLERANCE"20%"
CDS_LIB"passive"
CDS_LMAN_SYM_OUTLINE"-50,0,50,-50"
CLS_PN"G105-0F475-BM"
$LOCATION"C170"
CDS_LOCATION"C170"
$SEC"1"
CDS_SEC"1";
"2"
$PN"2"3;
"1"
$PN"1"11;
%"CAPACITOR"
"2","(-2950,5700)","0","passive","I283";
;
VALUE"0.1UF"
VOLTAGE"10V"
PACKAGE"0402"
TOLERANCE"10%"
CLS_PN"G105-0B104-CK"
CDS_LMAN_SYM_OUTLINE"-50,0,50,-50"
CDS_LIB"passive"
$LOCATION"C178"
CDS_LOCATION"C178"
$SEC"1"
CDS_SEC"1";
"2"
$PN"2"1;
"1"
$PN"1"10;
%"VCC"
"1","(-4300,4700)","0","cls","I284";
;
HDL_POWER"XP3R3V_FPGA"
VOLTAGE"3.3V"
BODY_TYPE"PLUMBING"
CDS_LMAN_SYM_OUTLINE"-250,250,250,-250"
CDS_LIB"cls";
"$PIN0"11;
%"VCC"
"1","(-2450,6150)","0","cls","I285";
;
HDL_POWER"XP1R0V_FPGA"
VOLTAGE"1.0V"
BODY_TYPE"PLUMBING"
CDS_LIB"cls"
CDS_LMAN_SYM_OUTLINE"-250,250,250,-250";
"$PIN0"10;
%"VCC"
"1","(-6450,950)","0","cls","I286";
;
VOLTAGE"1.0V"
HDL_POWER"XP1R0V_FPGA"
CDS_LMAN_SYM_OUTLINE"-250,250,250,-250"
CDS_LIB"cls"
BODY_TYPE"PLUMBING";
"$PIN0"9;
%"VCC"
"1","(-7150,-200)","0","cls","I287";
;
VOLTAGE"1.2V"
HDL_POWER"XP1R2V_FPGA"
CDS_LMAN_SYM_OUTLINE"-250,250,250,-250"
CDS_LIB"cls"
BODY_TYPE"PLUMBING";
"$PIN0"8;
%"VCC"
"1","(-6050,7600)","0","cls","I288";
;
HDL_POWER"XP1R8V_FPGA"
VOLTAGE"1.8V"
BODY_TYPE"PLUMBING"
CDS_LIB"cls"
CDS_LMAN_SYM_OUTLINE"-250,250,250,-250";
"$PIN0"7;
%"VCC"
"1","(-4300,2600)","0","cls","I289";
;
HDL_POWER"XP2R5V_FPGA"
VOLTAGE"2.5V"
BODY_TYPE"PLUMBING"
CDS_LMAN_SYM_OUTLINE"-250,250,250,-250"
CDS_LIB"cls";
"$PIN0"6;
%"CAPACITOR"
"2","(-4950,2050)","0","passive","I290";
;
PACKAGE"0805"
VOLTAGE"10V"
VALUE"22UF"
CLS_PN"G107-0F226-CM"
TOLERANCE"20%"
CDS_LMAN_SYM_OUTLINE"-50,0,50,-50"
CDS_LIB"passive"
$LOCATION"C291"
CDS_LOCATION"C291"
$SEC"1"
CDS_SEC"1";
"2"
$PN"2"5;
"1"
$PN"1"6;
%"CAPACITOR"
"2","(-4600,2050)","0","passive","I291";
;
PACKAGE"0805"
VOLTAGE"10V"
VALUE"22UF"
CLS_PN"G107-0F226-CM"
TOLERANCE"20%"
CDS_LMAN_SYM_OUTLINE"-50,0,50,-50"
CDS_LIB"passive"
$LOCATION"C292"
CDS_LOCATION"C292"
$SEC"1"
CDS_SEC"1";
"2"
$PN"2"5;
"1"
$PN"1"6;
%"CAPACITOR"
"2","(-6050,2050)","0","passive","I292";
;
VALUE"4.7UF"
PACKAGE"0402"
VOLTAGE"6.3V"
CDS_LIB"passive"
CDS_LMAN_SYM_OUTLINE"-50,0,50,-50"
CLS_PN"G105-0F475-BM"
TOLERANCE"20%"
$LOCATION"C93"
CDS_LOCATION"C93"
$SEC"1"
CDS_SEC"1";
"2"
$PN"2"5;
"1"
$PN"1"6;
%"GND_SG"
"1","(-11000,1700)","0","cls","I293";
;
HDL_POWER"SG"
BODY_TYPE"PLUMBING"
CDS_LMAN_SYM_OUTLINE"0,0,100,-50"
CDS_LIB"cls";
"SGND"5;
%"FERRITEBEAD"
"1","(-8400,-350)","0","passive","I36";
;
VALUE"120OHM"
PACKAGE"0603"
TOLERANCE"25%"
CLS_PN"G191-10100-01"
CDS_LMAN_SYM_OUTLINE"0,0,200,-100"
CDS_LIB"passive"
$LOCATION"L35"
CDS_LOCATION"L35"
$SEC"1"
CDS_SEC"1";
"2"
$PN"2"8;
"1"
$PN"1"13;
%"FERRITEBEAD"
"1","(-7650,750)","0","passive","I37";
;
VALUE"120OHM"
PACKAGE"0603"
TOLERANCE"25%"
CLS_PN"G191-10100-01"
CDS_LIB"passive"
CDS_LMAN_SYM_OUTLINE"0,0,200,-100"
$LOCATION"L34"
CDS_LOCATION"L34"
$SEC"1"
CDS_SEC"1";
"2"
$PN"2"9;
"1"
$PN"1"16;
%"GND_SG"
"1","(-10200,50)","0","cls","I5";
;
HDL_POWER"SG"
BODY_TYPE"PLUMBING"
CDS_LIB"cls"
CDS_LMAN_SYM_OUTLINE"0,0,100,-50";
"SGND"4;
%"GND_SG"
"1","(-11000,3950)","0","cls","I59";
;
HDL_POWER"SG"
BODY_TYPE"PLUMBING"
CDS_LMAN_SYM_OUTLINE"0,0,100,-50"
CDS_LIB"cls";
"SGND"3;
%"GND_SG"
"1","(-11000,6800)","0","cls","I64";
;
HDL_POWER"SG"
BODY_TYPE"PLUMBING"
CDS_LIB"cls"
CDS_LMAN_SYM_OUTLINE"0,0,100,-50";
"SGND"2;
%"GND_SG"
"1","(-11000,5300)","0","cls","I73";
;
HDL_POWER"SG"
BODY_TYPE"PLUMBING"
CDS_LIB"cls"
CDS_LMAN_SYM_OUTLINE"0,0,100,-50";
"SGND"1;
END.
